# BASEBOARD_FAB2 (Tioga Pass) — schematic netlist excerpt (pin names and nets, part order shuffled) for the footprints in the layout excerpt that follows; sources: Cadence DE-HDL packaged netlist, KiCad conversion of Wiwynn_Tioga_Pass_MB.brd

R7W17  RES  0.0 5% CHIP  pkg 0402  page 119 : A = FM_THROTTLE_R2_N ; B = FM_THROTTLE_N
R2N9  RES  10.0K 1% CHIP  pkg 0402  page 133 : A = P3V3_STBY ; B = PU_10GBE_LOM_PCI_DISABLE_N
R1F4  RES  2 1.0% CHIP  pkg 0402  page 100 : A = M_G_CPU_VREF ; B = M_G_VREF

(kicad_pcb
	(version 20260206)
	(generator "pcbnew")
	(generator_version "10.0")
	(general
		(thickness 1.6)
		(legacy_teardrops no)
	)
	(paper "A4")
	(title_block
		(title "Wiwynn_Tioga_Pass_MB.brd")
		(comment 1 "Tioga Pass / footprints 1588-1590 of 4770")
	)
	(layers
		(0 "F.Cu" signal "TOP")
		(4 "In1.Cu" signal "L2GND")
		(6 "In2.Cu" signal "L3")
		(8 "In3.Cu" signal "L4GND")
		(10 "In4.Cu" signal "L5")
		(12 "In5.Cu" signal "L6GND")
		(14 "In6.Cu" signal "L7VCC")
		(16 "In7.Cu" signal "L8VCC")
		(18 "In8.Cu" signal "L9GND")
		(20 "In9.Cu" signal "L10")
		(22 "In10.Cu" signal "L11GND")
		(24 "In11.Cu" signal "L12")
		(26 "In12.Cu" signal "L13GND")
		(2 "B.Cu" signal "BOTTOM")
		(9 "F.Adhes" user "F.Adhesive")
		(11 "B.Adhes" user "B.Adhesive")
		(13 "F.Paste" user "Package Geometry/Pastemask Top")
		(15 "B.Paste" user "Package Geometry/Pastemask Bottom")
		(5 "F.SilkS" user "Ref Des/Silkscreen Top")
		(7 "B.SilkS" user "Ref Des/Silkscreen Bottom")
		(1 "F.Mask" user "Board Geometry/Soldermask Top")
		(3 "B.Mask" user "Board Geometry/Soldermask Bottom")
		(17 "Dwgs.User" user "User.Drawings")
		(19 "Cmts.User" user "User.Comments")
		(21 "Eco1.User" user "User.Eco1")
		(23 "Eco2.User" user "User.Eco2")
		(25 "Edge.Cuts" user "Board Geometry/Outline")
		(27 "Margin" user)
		(31 "F.CrtYd" user "Package Geometry/Place Bound Top")
		(29 "B.CrtYd" user "Package Geometry/Place Bound Bottom")
		(35 "F.Fab" user "Ref Des/Assembly Top")
		(33 "B.Fab" user "Ref Des/Assembly Bottom")
	)
	(footprint ""
		(layer "F.Cu")
		(at 407.73604 -112.32642 90)
		(property "Reference" "R7W17"
			(at -0.8382 -0.67818 90)
			(unlocked yes)
			(layer "F.SilkS")
			(effects
				(font
					(size 0.4064 0.254)
					(thickness 0.1524)
				)
				(justify left)
			)
		)
		(property "Value" ""
			(at 0 0 90)
			(layer "F.Fab")
			(effects
				(font
					(size 1.27 1.27)
				)
			)
		)
		(duplicate_pad_numbers_are_jumpers no)
		(fp_poly
			(pts
				(xy -0.2794 -0.1016) (xy 0.2794 -0.1016) (xy 0.2794 0.9906) (xy -0.2794 0.9906)
			)
			(stroke
				(width 0)
				(type default)
			)
			(fill no)
			(layer "F.CrtYd")
		)
		(fp_line
			(start 0.2794 -0.1016)
			(end -0.2794 -0.1016)
			(stroke
				(width 0.1)
				(type default)
			)
			(layer "F.Fab")
		)
		(fp_line
			(start -0.2794 -0.1016)
			(end -0.2794 0.9906)
			(stroke
				(width 0.1)
				(type default)
			)
			(layer "F.Fab")
		)
		(fp_line
			(start 0.2794 0.9906)
			(end 0.2794 -0.1016)
			(stroke
				(width 0.1)
				(type default)
			)
			(layer "F.Fab")
		)
		(fp_line
			(start -0.2794 0.9906)
			(end 0.2794 0.9906)
			(stroke
				(width 0.1)
				(type default)
			)
			(layer "F.Fab")
		)
		(pad "1" smd rect
			(at 0 0 90)
			(size 0.508 0.508)
			(layers "F.Cu" "F.Mask" "F.Paste")
			(net "FM_THROTTLE_R2_N")
		)
		(pad "2" smd rect
			(at 0 0.889 90)
			(size 0.508 0.508)
			(layers "F.Cu" "F.Mask" "F.Paste")
			(net "FM_THROTTLE_N")
		)
		(zone
			(layer "F.Cu")
			(hatch none 0.5)
			(connect_pads
				(clearance 0)
			)
			(min_thickness 0.25)
			(keepout
				(tracks allowed)
				(vias not_allowed)
				(pads allowed)
				(copperpour not_allowed)
				(footprints allowed)
			)
			(placement
				(enabled no)
				(sheetname "")
			)
			(fill
				(thermal_gap 0.5)
				(thermal_bridge_width 0.5)
				(island_removal_mode 0)
			)
			(polygon
				(pts
					(xy 407.99004 -112.07242) (xy 407.99004 -112.58042) (xy 408.37104 -112.58042) (xy 408.37104 -112.07242)
				)
			)
		)
		(zone
			(layer "F.Cu")
			(hatch none 0.5)
			(connect_pads
				(clearance 0)
			)
			(min_thickness 0.25)
			(keepout
				(tracks not_allowed)
				(vias allowed)
				(pads allowed)
				(copperpour not_allowed)
				(footprints allowed)
			)
			(placement
				(enabled no)
				(sheetname "")
			)
			(fill
				(thermal_gap 0.5)
				(thermal_bridge_width 0.5)
				(island_removal_mode 0)
			)
			(polygon
				(pts
					(xy 408.37104 -112.07242) (xy 408.37104 -112.58042) (xy 407.99004 -112.58042) (xy 407.99004 -112.07242)
				)
			)
		)
	)
	(footprint ""
		(layer "F.Cu")
		(at 28.242006 -22.941534)
		(property "Reference" "R1F4"
			(at 0 0 0)
			(layer "F.SilkS")
			(hide yes)
			(effects
				(font
					(size 1.27 1.27)
				)
			)
		)
		(property "Value" ""
			(at 0 0 0)
			(layer "F.Fab")
			(effects
				(font
					(size 1.27 1.27)
				)
			)
		)
		(duplicate_pad_numbers_are_jumpers no)
		(fp_poly
			(pts
				(xy -0.2794 -0.1016) (xy 0.2794 -0.1016) (xy 0.2794 0.9906) (xy -0.2794 0.9906)
			)
			(stroke
				(width 0)
				(type default)
			)
			(fill no)
			(layer "F.CrtYd")
		)
		(fp_line
			(start -0.2794 -0.1016)
			(end -0.2794 0.9906)
			(stroke
				(width 0.1)
				(type default)
			)
			(layer "F.Fab")
		)
		(fp_line
			(start -0.2794 0.9906)
			(end 0.2794 0.9906)
			(stroke
				(width 0.1)
				(type default)
			)
			(layer "F.Fab")
		)
		(fp_line
			(start 0.2794 -0.1016)
			(end -0.2794 -0.1016)
			(stroke
				(width 0.1)
				(type default)
			)
			(layer "F.Fab")
		)
		(fp_line
			(start 0.2794 0.9906)
			(end 0.2794 -0.1016)
			(stroke
				(width 0.1)
				(type default)
			)
			(layer "F.Fab")
		)
		(pad "1" smd rect
			(at 0 0)
			(size 0.508 0.508)
			(layers "F.Cu" "F.Mask" "F.Paste")
			(net "M_G_CPU_VREF")
		)
		(pad "2" smd rect
			(at 0 0.889)
			(size 0.508 0.508)
			(layers "F.Cu" "F.Mask" "F.Paste")
			(net "M_G_VREF")
		)
		(zone
			(layer "F.Cu")
			(hatch none 0.5)
			(connect_pads
				(clearance 0)
			)
			(min_thickness 0.25)
			(keepout
				(tracks allowed)
				(vias not_allowed)
				(pads allowed)
				(copperpour not_allowed)
				(footprints allowed)
			)
			(placement
				(enabled no)
				(sheetname "")
			)
			(fill
				(thermal_gap 0.5)
				(thermal_bridge_width 0.5)
				(island_removal_mode 0)
			)
			(polygon
				(pts
					(xy 27.988006 -22.687534) (xy 28.496006 -22.687534) (xy 28.496006 -22.306534) (xy 27.988006 -22.306534)
				)
			)
		)
		(zone
			(layer "F.Cu")
			(hatch none 0.5)
			(connect_pads
				(clearance 0)
			)
			(min_thickness 0.25)
			(keepout
				(tracks not_allowed)
				(vias allowed)
				(pads allowed)
				(copperpour not_allowed)
				(footprints allowed)
			)
			(placement
				(enabled no)
				(sheetname "")
			)
			(fill
				(thermal_gap 0.5)
				(thermal_bridge_width 0.5)
				(island_removal_mode 0)
			)
			(polygon
				(pts
					(xy 27.988006 -22.306534) (xy 28.496006 -22.306534) (xy 28.496006 -22.687534) (xy 27.988006 -22.687534)
				)
			)
		)
	)
	(footprint ""
		(layer "F.Cu")
		(at 406.7302 -104.648 -90)
		(property "Reference" "R2N9"
			(at 0 0 270)
			(layer "F.SilkS")
			(hide yes)
			(effects
				(font
					(size 1.27 1.27)
				)
			)
		)
		(property "Value" ""
			(at 0 0 270)
			(layer "F.Fab")
			(effects
				(font
					(size 1.27 1.27)
				)
			)
		)
		(duplicate_pad_numbers_are_jumpers no)
		(fp_poly
			(pts
				(xy -0.2794 -0.1016) (xy 0.2794 -0.1016) (xy 0.2794 0.9906) (xy -0.2794 0.9906)
			)
			(stroke
				(width 0)
				(type default)
			)
			(fill no)
			(layer "F.CrtYd")
		)
		(fp_line
			(start -0.2794 0.9906)
			(end 0.2794 0.9906)
			(stroke
				(width 0.1)
				(type default)
			)
			(layer "F.Fab")
		)
		(fp_line
			(start 0.2794 0.9906)
			(end 0.2794 -0.1016)
			(stroke
				(width 0.1)
				(type default)
			)
			(layer "F.Fab")
		)
		(fp_line
			(start -0.2794 -0.1016)
			(end -0.2794 0.9906)
			(stroke
				(width 0.1)
				(type default)
			)
			(layer "F.Fab")
		)
		(fp_line
			(start 0.2794 -0.1016)
			(end -0.2794 -0.1016)
			(stroke
				(width 0.1)
				(type default)
			)
			(layer "F.Fab")
		)
		(pad "1" smd rect
			(at 0 0 270)
			(size 0.508 0.508)
			(layers "F.Cu" "F.Mask" "F.Paste")
			(net "P3V3_STBY")
		)
		(pad "2" smd rect
			(at 0 0.889 270)
			(size 0.508 0.508)
			(layers "F.Cu" "F.Mask" "F.Paste")
			(net "PU_10GBE_LOM_PCI_DISABLE_N")
		)
		(zone
			(layer "F.Cu")
			(hatch none 0.5)
			(connect_pads
				(clearance 0)
			)
			(min_thickness 0.25)
			(keepout
				(tracks not_allowed)
				(vias allowed)
				(pads allowed)
				(copperpour not_allowed)
				(footprints allowed)
			)
			(placement
				(enabled no)
				(sheetname "")
			)
			(fill
				(thermal_gap 0.5)
				(thermal_bridge_width 0.5)
				(island_removal_mode 0)
			)
			(polygon
				(pts
					(xy 406.0952 -104.902) (xy 406.0952 -104.394) (xy 406.4762 -104.394) (xy 406.4762 -104.902)
				)
			)
		)
		(zone
			(layer "F.Cu")
			(hatch none 0.5)
			(connect_pads
				(clearance 0)
			)
			(min_thickness 0.25)
			(keepout
				(tracks allowed)
				(vias not_allowed)
				(pads allowed)
				(copperpour not_allowed)
				(footprints allowed)
			)
			(placement
				(enabled no)
				(sheetname "")
			)
			(fill
				(thermal_gap 0.5)
				(thermal_bridge_width 0.5)
				(island_removal_mode 0)
			)
			(polygon
				(pts
					(xy 406.4762 -104.902) (xy 406.4762 -104.394) (xy 406.0952 -104.394) (xy 406.0952 -104.902)
				)
			)
		)
	)
)
